(kicad_pcb
	(version 20260206)
	(generator "pcbnew")
	(generator_version "10.0")
	(general
		(thickness 1.6)
		(legacy_teardrops no)
	)
	(paper "A4")
	(title_block
		(title "03242023_DA0F0TMBIJ0_F0T_Motherboard_J_brd_V01_OCP.brd")
		(comment 1 "Grand Teton / footprints 4291-4297 of 6105")
	)
	(layers
		(0 "F.Cu" signal "TOP")
		(4 "In1.Cu" signal "GND")
		(6 "In2.Cu" signal "IN1")
		(8 "In3.Cu" signal "GND1")
		(10 "In4.Cu" signal "IN2")
		(12 "In5.Cu" signal "GND2")
		(14 "In6.Cu" signal "IN3")
		(16 "In7.Cu" signal "GND3")
		(18 "In8.Cu" signal "VCC")
		(20 "In9.Cu" signal "VCC1")
		(22 "In10.Cu" signal "GND4")
		(24 "In11.Cu" signal "IN4")
		(26 "In12.Cu" signal "GND5")
		(28 "In13.Cu" signal "IN5")
		(30 "In14.Cu" signal "GND6")
		(32 "In15.Cu" signal "IN6")
		(34 "In16.Cu" signal "GND7")
		(2 "B.Cu" signal "BOTTOM")
		(9 "F.Adhes" user "F.Adhesive")
		(11 "B.Adhes" user "B.Adhesive")
		(13 "F.Paste" user "Package Geometry/Pastemask Top")
		(15 "B.Paste" user "Package Geometry/Pastemask Bottom")
		(5 "F.SilkS" user "Ref Des/Silkscreen Top")
		(7 "B.SilkS" user "Ref Des/Silkscreen Bottom")
		(1 "F.Mask" user "Board Geometry/Soldermask Top")
		(3 "B.Mask" user "Board Geometry/Soldermask Bottom")
		(17 "Dwgs.User" user "User.Drawings")
		(19 "Cmts.User" user "User.Comments")
		(21 "Eco1.User" user "User.Eco1")
		(23 "Eco2.User" user "User.Eco2")
		(25 "Edge.Cuts" user "Board Geometry/Outline")
		(27 "Margin" user)
		(31 "F.CrtYd" user "Package Geometry/Place Bound Top")
		(29 "B.CrtYd" user "Package Geometry/Place Bound Bottom")
		(35 "F.Fab" user "Ref Des/Assembly Top")
		(33 "B.Fab" user "Ref Des/Assembly Bottom")
	)
	(footprint ""
		(layer "B.Cu")
		(at 351.26803 -359.995216 180)
		(property "Reference" "R2591"
			(at 0 0 0)
			(layer "B.SilkS")
			(hide yes)
			(effects
				(font
					(size 1.27 1.27)
				)
				(justify mirror)
			)
		)
		(property "Value" ""
			(at 0 0 0)
			(layer "B.Fab")
			(effects
				(font
					(size 1.27 1.27)
				)
				(justify mirror)
			)
		)
		(duplicate_pad_numbers_are_jumpers no)
		(fp_line
			(start 0.7874 0.4064)
			(end 0.7874 -0.4064)
			(stroke
				(width 0.1524)
				(type default)
			)
			(layer "B.SilkS")
		)
		(fp_line
			(start 0.7874 -0.4064)
			(end -0.7874 -0.4064)
			(stroke
				(width 0.1524)
				(type default)
			)
			(layer "B.SilkS")
		)
		(fp_line
			(start -0.7874 0.4064)
			(end 0.7874 0.4064)
			(stroke
				(width 0.1524)
				(type default)
			)
			(layer "B.SilkS")
		)
		(fp_line
			(start -0.7874 -0.4064)
			(end -0.7874 0.4064)
			(stroke
				(width 0.1524)
				(type default)
			)
			(layer "B.SilkS")
		)
		(fp_line
			(start 0.67945 0.3048)
			(end 0.67945 -0.305054)
			(stroke
				(width 0.1)
				(type default)
			)
			(layer "B.Fab")
		)
		(fp_line
			(start 0.67945 -0.305054)
			(end 0.12065 -0.305054)
			(stroke
				(width 0.1)
				(type default)
			)
			(layer "B.Fab")
		)
		(fp_line
			(start 0.12065 0.3048)
			(end 0.67945 0.3048)
			(stroke
				(width 0.1)
				(type default)
			)
			(layer "B.Fab")
		)
		(fp_line
			(start 0.12065 0.2794)
			(end 0.12065 0.3048)
			(stroke
				(width 0.1)
				(type default)
			)
			(layer "B.Fab")
		)
		(fp_line
			(start 0.12065 -0.2794)
			(end -0.12065 -0.2794)
			(stroke
				(width 0.1)
				(type default)
			)
			(layer "B.Fab")
		)
		(fp_line
			(start 0.12065 -0.305054)
			(end 0.12065 -0.2794)
			(stroke
				(width 0.1)
				(type default)
			)
			(layer "B.Fab")
		)
		(fp_line
			(start -0.120396 0.3048)
			(end -0.120396 0.2794)
			(stroke
				(width 0.1)
				(type default)
			)
			(layer "B.Fab")
		)
		(fp_line
			(start -0.120396 0.2794)
			(end 0.12065 0.2794)
			(stroke
				(width 0.1)
				(type default)
			)
			(layer "B.Fab")
		)
		(fp_line
			(start -0.12065 -0.2794)
			(end -0.12065 -0.3048)
			(stroke
				(width 0.1)
				(type default)
			)
			(layer "B.Fab")
		)
		(fp_line
			(start -0.12065 -0.3048)
			(end -0.67945 -0.3048)
			(stroke
				(width 0.1)
				(type default)
			)
			(layer "B.Fab")
		)
		(fp_line
			(start -0.67945 0.3048)
			(end -0.120396 0.3048)
			(stroke
				(width 0.1)
				(type default)
			)
			(layer "B.Fab")
		)
		(fp_line
			(start -0.67945 -0.3048)
			(end -0.67945 0.3048)
			(stroke
				(width 0.1)
				(type default)
			)
			(layer "B.Fab")
		)
		(pad "1" smd circle
			(at 0.40005 0)
			(size 0 0)
			(layers "B.Cu" "B.Mask" "B.Paste")
			(net "FM_PVCCIN_CPU0_EN")
		)
		(pad "2" smd circle
			(at -0.40005 0)
			(size 0 0)
			(layers "B.Cu" "B.Mask" "B.Paste")
			(net "PVCCIN_CPU0_EN_R")
		)
	)
	(footprint ""
		(layer "B.Cu")
		(at 333.32928 -339.983572 -90)
		(property "Reference" "PR142"
			(at 0 0 90)
			(layer "B.SilkS")
			(hide yes)
			(effects
				(font
					(size 1.27 1.27)
				)
				(justify mirror)
			)
		)
		(property "Value" ""
			(at 0 0 90)
			(layer "B.Fab")
			(effects
				(font
					(size 1.27 1.27)
				)
				(justify mirror)
			)
		)
		(duplicate_pad_numbers_are_jumpers no)
		(fp_line
			(start -0.7874 0.4064)
			(end 0.7874 0.4064)
			(stroke
				(width 0.1524)
				(type default)
			)
			(layer "B.SilkS")
		)
		(fp_line
			(start 0.7874 0.4064)
			(end 0.7874 -0.4064)
			(stroke
				(width 0.1524)
				(type default)
			)
			(layer "B.SilkS")
		)
		(fp_line
			(start -0.7874 -0.4064)
			(end -0.7874 0.4064)
			(stroke
				(width 0.1524)
				(type default)
			)
			(layer "B.SilkS")
		)
		(fp_line
			(start 0.7874 -0.4064)
			(end -0.7874 -0.4064)
			(stroke
				(width 0.1524)
				(type default)
			)
			(layer "B.SilkS")
		)
		(fp_line
			(start -0.67945 0.3048)
			(end -0.120396 0.3048)
			(stroke
				(width 0.1)
				(type default)
			)
			(layer "B.Fab")
		)
		(fp_line
			(start -0.120396 0.3048)
			(end -0.120396 0.2794)
			(stroke
				(width 0.1)
				(type default)
			)
			(layer "B.Fab")
		)
		(fp_line
			(start 0.12065 0.3048)
			(end 0.67945 0.3048)
			(stroke
				(width 0.1)
				(type default)
			)
			(layer "B.Fab")
		)
		(fp_line
			(start 0.67945 0.3048)
			(end 0.67945 -0.305054)
			(stroke
				(width 0.1)
				(type default)
			)
			(layer "B.Fab")
		)
		(fp_line
			(start -0.120396 0.2794)
			(end 0.12065 0.2794)
			(stroke
				(width 0.1)
				(type default)
			)
			(layer "B.Fab")
		)
		(fp_line
			(start 0.12065 0.2794)
			(end 0.12065 0.3048)
			(stroke
				(width 0.1)
				(type default)
			)
			(layer "B.Fab")
		)
		(fp_line
			(start -0.12065 -0.2794)
			(end -0.12065 -0.3048)
			(stroke
				(width 0.1)
				(type default)
			)
			(layer "B.Fab")
		)
		(fp_line
			(start 0.12065 -0.2794)
			(end -0.12065 -0.2794)
			(stroke
				(width 0.1)
				(type default)
			)
			(layer "B.Fab")
		)
		(fp_line
			(start -0.67945 -0.3048)
			(end -0.67945 0.3048)
			(stroke
				(width 0.1)
				(type default)
			)
			(layer "B.Fab")
		)
		(fp_line
			(start -0.12065 -0.3048)
			(end -0.67945 -0.3048)
			(stroke
				(width 0.1)
				(type default)
			)
			(layer "B.Fab")
		)
		(fp_line
			(start 0.12065 -0.305054)
			(end 0.12065 -0.2794)
			(stroke
				(width 0.1)
				(type default)
			)
			(layer "B.Fab")
		)
		(fp_line
			(start 0.67945 -0.305054)
			(end 0.12065 -0.305054)
			(stroke
				(width 0.1)
				(type default)
			)
			(layer "B.Fab")
		)
		(pad "1" smd circle
			(at 0.40005 0 90)
			(size 0 0)
			(layers "B.Cu" "B.Mask" "B.Paste")
			(net "PVCCIN_CPU0_VOS6")
		)
		(pad "2" smd circle
			(at -0.40005 0 90)
			(size 0 0)
			(layers "B.Cu" "B.Mask" "B.Paste")
			(net "PVCCIN_CPU0")
		)
	)
	(footprint ""
		(layer "B.Cu")
		(at 157.24886 -11.250168 90)
		(property "Reference" "R3114"
			(at 0 0 90)
			(layer "B.SilkS")
			(hide yes)
			(effects
				(font
					(size 1.27 1.27)
				)
				(justify mirror)
			)
		)
		(property "Value" ""
			(at 0 0 90)
			(layer "B.Fab")
			(effects
				(font
					(size 1.27 1.27)
				)
				(justify mirror)
			)
		)
		(duplicate_pad_numbers_are_jumpers no)
		(fp_line
			(start 0.7874 -0.4064)
			(end -0.7874 -0.4064)
			(stroke
				(width 0.1524)
				(type default)
			)
			(layer "B.SilkS")
		)
		(fp_line
			(start -0.7874 -0.4064)
			(end -0.7874 0.4064)
			(stroke
				(width 0.1524)
				(type default)
			)
			(layer "B.SilkS")
		)
		(fp_line
			(start 0.7874 0.4064)
			(end 0.7874 -0.4064)
			(stroke
				(width 0.1524)
				(type default)
			)
			(layer "B.SilkS")
		)
		(fp_line
			(start -0.7874 0.4064)
			(end 0.7874 0.4064)
			(stroke
				(width 0.1524)
				(type default)
			)
			(layer "B.SilkS")
		)
		(fp_line
			(start 0.67945 -0.305054)
			(end 0.12065 -0.305054)
			(stroke
				(width 0.1)
				(type default)
			)
			(layer "B.Fab")
		)
		(fp_line
			(start 0.12065 -0.305054)
			(end 0.12065 -0.2794)
			(stroke
				(width 0.1)
				(type default)
			)
			(layer "B.Fab")
		)
		(fp_line
			(start -0.12065 -0.3048)
			(end -0.67945 -0.3048)
			(stroke
				(width 0.1)
				(type default)
			)
			(layer "B.Fab")
		)
		(fp_line
			(start -0.67945 -0.3048)
			(end -0.67945 0.3048)
			(stroke
				(width 0.1)
				(type default)
			)
			(layer "B.Fab")
		)
		(fp_line
			(start 0.12065 -0.2794)
			(end -0.12065 -0.2794)
			(stroke
				(width 0.1)
				(type default)
			)
			(layer "B.Fab")
		)
		(fp_line
			(start -0.12065 -0.2794)
			(end -0.12065 -0.3048)
			(stroke
				(width 0.1)
				(type default)
			)
			(layer "B.Fab")
		)
		(fp_line
			(start 0.12065 0.2794)
			(end 0.12065 0.3048)
			(stroke
				(width 0.1)
				(type default)
			)
			(layer "B.Fab")
		)
		(fp_line
			(start -0.120396 0.2794)
			(end 0.12065 0.2794)
			(stroke
				(width 0.1)
				(type default)
			)
			(layer "B.Fab")
		)
		(fp_line
			(start 0.67945 0.3048)
			(end 0.67945 -0.305054)
			(stroke
				(width 0.1)
				(type default)
			)
			(layer "B.Fab")
		)
		(fp_line
			(start 0.12065 0.3048)
			(end 0.67945 0.3048)
			(stroke
				(width 0.1)
				(type default)
			)
			(layer "B.Fab")
		)
		(fp_line
			(start -0.120396 0.3048)
			(end -0.120396 0.2794)
			(stroke
				(width 0.1)
				(type default)
			)
			(layer "B.Fab")
		)
		(fp_line
			(start -0.67945 0.3048)
			(end -0.120396 0.3048)
			(stroke
				(width 0.1)
				(type default)
			)
			(layer "B.Fab")
		)
		(pad "1" smd circle
			(at 0.40005 0 270)
			(size 0 0)
			(layers "B.Cu" "B.Mask" "B.Paste")
			(net "SMB_FAN_3V3AUX_SDA")
		)
		(pad "2" smd circle
			(at -0.40005 0 270)
			(size 0 0)
			(layers "B.Cu" "B.Mask" "B.Paste")
			(net "SMB_FAN_3V3AUX_R_SDA")
		)
	)
	(footprint ""
		(layer "B.Cu")
		(at 116.40312 -248.49836 -90)
		(property "Reference" "C314"
			(at 0 0 90)
			(layer "B.SilkS")
			(hide yes)
			(effects
				(font
					(size 1.27 1.27)
				)
				(justify mirror)
			)
		)
		(property "Value" ""
			(at 0 0 90)
			(layer "B.Fab")
			(effects
				(font
					(size 1.27 1.27)
				)
				(justify mirror)
			)
		)
		(duplicate_pad_numbers_are_jumpers no)
		(fp_line
			(start -1.524 0.762)
			(end 1.524 0.762)
			(stroke
				(width 0.1524)
				(type default)
			)
			(layer "B.SilkS")
		)
		(fp_line
			(start 1.524 0.762)
			(end 1.524 -0.762)
			(stroke
				(width 0.1524)
				(type default)
			)
			(layer "B.SilkS")
		)
		(fp_line
			(start -1.524 -0.762)
			(end -1.524 0.762)
			(stroke
				(width 0.1524)
				(type default)
			)
			(layer "B.SilkS")
		)
		(fp_line
			(start 1.524 -0.762)
			(end -1.524 -0.762)
			(stroke
				(width 0.1524)
				(type default)
			)
			(layer "B.SilkS")
		)
		(fp_line
			(start -1.1049 0.724916)
			(end -1.1049 -0.724916)
			(stroke
				(width 0.1)
				(type default)
			)
			(layer "B.Fab")
		)
		(fp_line
			(start 1.1049 0.724916)
			(end -1.1049 0.724916)
			(stroke
				(width 0.1)
				(type default)
			)
			(layer "B.Fab")
		)
		(fp_line
			(start -1.1049 -0.724916)
			(end 1.1049 -0.724916)
			(stroke
				(width 0.1)
				(type default)
			)
			(layer "B.Fab")
		)
		(fp_line
			(start 1.1049 -0.724916)
			(end 1.1049 0.724916)
			(stroke
				(width 0.1)
				(type default)
			)
			(layer "B.Fab")
		)
		(pad "1" smd rect
			(at 0.889 0 270)
			(size 1.016 1.27)
			(layers "B.Cu" "B.Mask" "B.Paste")
			(net "PVCCIN_CPU1")
		)
		(pad "2" smd rect
			(at -0.889 0 270)
			(size 1.016 1.27)
			(layers "B.Cu" "B.Mask" "B.Paste")
			(net "GND")
		)
	)
	(footprint ""
		(layer "B.Cu")
		(at 343.050368 -31.678372 180)
		(property "Reference" "R1458"
			(at 0 0 0)
			(layer "B.SilkS")
			(hide yes)
			(effects
				(font
					(size 1.27 1.27)
				)
				(justify mirror)
			)
		)
		(property "Value" ""
			(at 0 0 0)
			(layer "B.Fab")
			(effects
				(font
					(size 1.27 1.27)
				)
				(justify mirror)
			)
		)
		(duplicate_pad_numbers_are_jumpers no)
		(fp_line
			(start 0.7874 0.4064)
			(end 0.7874 -0.4064)
			(stroke
				(width 0.1524)
				(type default)
			)
			(layer "B.SilkS")
		)
		(fp_line
			(start 0.7874 -0.4064)
			(end -0.7874 -0.4064)
			(stroke
				(width 0.1524)
				(type default)
			)
			(layer "B.SilkS")
		)
		(fp_line
			(start -0.7874 0.4064)
			(end 0.7874 0.4064)
			(stroke
				(width 0.1524)
				(type default)
			)
			(layer "B.SilkS")
		)
		(fp_line
			(start -0.7874 -0.4064)
			(end -0.7874 0.4064)
			(stroke
				(width 0.1524)
				(type default)
			)
			(layer "B.SilkS")
		)
		(fp_line
			(start 0.67945 0.3048)
			(end 0.67945 -0.305054)
			(stroke
				(width 0.1)
				(type default)
			)
			(layer "B.Fab")
		)
		(fp_line
			(start 0.67945 -0.305054)
			(end 0.12065 -0.305054)
			(stroke
				(width 0.1)
				(type default)
			)
			(layer "B.Fab")
		)
		(fp_line
			(start 0.12065 0.3048)
			(end 0.67945 0.3048)
			(stroke
				(width 0.1)
				(type default)
			)
			(layer "B.Fab")
		)
		(fp_line
			(start 0.12065 0.2794)
			(end 0.12065 0.3048)
			(stroke
				(width 0.1)
				(type default)
			)
			(layer "B.Fab")
		)
		(fp_line
			(start 0.12065 -0.2794)
			(end -0.12065 -0.2794)
			(stroke
				(width 0.1)
				(type default)
			)
			(layer "B.Fab")
		)
		(fp_line
			(start 0.12065 -0.305054)
			(end 0.12065 -0.2794)
			(stroke
				(width 0.1)
				(type default)
			)
			(layer "B.Fab")
		)
		(fp_line
			(start -0.120396 0.3048)
			(end -0.120396 0.2794)
			(stroke
				(width 0.1)
				(type default)
			)
			(layer "B.Fab")
		)
		(fp_line
			(start -0.120396 0.2794)
			(end 0.12065 0.2794)
			(stroke
				(width 0.1)
				(type default)
			)
			(layer "B.Fab")
		)
		(fp_line
			(start -0.12065 -0.2794)
			(end -0.12065 -0.3048)
			(stroke
				(width 0.1)
				(type default)
			)
			(layer "B.Fab")
		)
		(fp_line
			(start -0.12065 -0.3048)
			(end -0.67945 -0.3048)
			(stroke
				(width 0.1)
				(type default)
			)
			(layer "B.Fab")
		)
		(fp_line
			(start -0.67945 0.3048)
			(end -0.120396 0.3048)
			(stroke
				(width 0.1)
				(type default)
			)
			(layer "B.Fab")
		)
		(fp_line
			(start -0.67945 -0.3048)
			(end -0.67945 0.3048)
			(stroke
				(width 0.1)
				(type default)
			)
			(layer "B.Fab")
		)
		(pad "1" smd circle
			(at 0.40005 0)
			(size 0 0)
			(layers "B.Cu" "B.Mask" "B.Paste")
			(net "P3V3_AUX")
		)
		(pad "2" smd circle
			(at -0.40005 0)
			(size 0 0)
			(layers "B.Cu" "B.Mask" "B.Paste")
			(net "IRQ_SMI_ACTIVE_N")
		)
	)
	(footprint ""
		(layer "B.Cu")
		(at 421.92448 -156.378148 90)
		(property "Reference" "PR443"
			(at 0 0 90)
			(layer "B.SilkS")
			(hide yes)
			(effects
				(font
					(size 1.27 1.27)
				)
				(justify mirror)
			)
		)
		(property "Value" ""
			(at 0 0 90)
			(layer "B.Fab")
			(effects
				(font
					(size 1.27 1.27)
				)
				(justify mirror)
			)
		)
		(duplicate_pad_numbers_are_jumpers no)
		(fp_line
			(start 0.7874 -0.4064)
			(end -0.7874 -0.4064)
			(stroke
				(width 0.1524)
				(type default)
			)
			(layer "B.SilkS")
		)
		(fp_line
			(start -0.7874 -0.4064)
			(end -0.7874 0.4064)
			(stroke
				(width 0.1524)
				(type default)
			)
			(layer "B.SilkS")
		)
		(fp_line
			(start 0.7874 0.4064)
			(end 0.7874 -0.4064)
			(stroke
				(width 0.1524)
				(type default)
			)
			(layer "B.SilkS")
		)
		(fp_line
			(start -0.7874 0.4064)
			(end 0.7874 0.4064)
			(stroke
				(width 0.1524)
				(type default)
			)
			(layer "B.SilkS")
		)
		(fp_line
			(start 0.67945 -0.305054)
			(end 0.12065 -0.305054)
			(stroke
				(width 0.1)
				(type default)
			)
			(layer "B.Fab")
		)
		(fp_line
			(start 0.12065 -0.305054)
			(end 0.12065 -0.2794)
			(stroke
				(width 0.1)
				(type default)
			)
			(layer "B.Fab")
		)
		(fp_line
			(start -0.12065 -0.3048)
			(end -0.67945 -0.3048)
			(stroke
				(width 0.1)
				(type default)
			)
			(layer "B.Fab")
		)
		(fp_line
			(start -0.67945 -0.3048)
			(end -0.67945 0.3048)
			(stroke
				(width 0.1)
				(type default)
			)
			(layer "B.Fab")
		)
		(fp_line
			(start 0.12065 -0.2794)
			(end -0.12065 -0.2794)
			(stroke
				(width 0.1)
				(type default)
			)
			(layer "B.Fab")
		)
		(fp_line
			(start -0.12065 -0.2794)
			(end -0.12065 -0.3048)
			(stroke
				(width 0.1)
				(type default)
			)
			(layer "B.Fab")
		)
		(fp_line
			(start 0.12065 0.2794)
			(end 0.12065 0.3048)
			(stroke
				(width 0.1)
				(type default)
			)
			(layer "B.Fab")
		)
		(fp_line
			(start -0.120396 0.2794)
			(end 0.12065 0.2794)
			(stroke
				(width 0.1)
				(type default)
			)
			(layer "B.Fab")
		)
		(fp_line
			(start 0.67945 0.3048)
			(end 0.67945 -0.305054)
			(stroke
				(width 0.1)
				(type default)
			)
			(layer "B.Fab")
		)
		(fp_line
			(start 0.12065 0.3048)
			(end 0.67945 0.3048)
			(stroke
				(width 0.1)
				(type default)
			)
			(layer "B.Fab")
		)
		(fp_line
			(start -0.120396 0.3048)
			(end -0.120396 0.2794)
			(stroke
				(width 0.1)
				(type default)
			)
			(layer "B.Fab")
		)
		(fp_line
			(start -0.67945 0.3048)
			(end -0.120396 0.3048)
			(stroke
				(width 0.1)
				(type default)
			)
			(layer "B.Fab")
		)
		(pad "1" smd circle
			(at 0.40005 0 270)
			(size 0 0)
			(layers "B.Cu" "B.Mask" "B.Paste")
			(net "P3V3")
		)
		(pad "2" smd circle
			(at -0.40005 0 270)
			(size 0 0)
			(layers "B.Cu" "B.Mask" "B.Paste")
			(net "PVCCFA_EHV_CPU0_PVCC")
		)
	)
	(footprint ""
		(layer "B.Cu")
		(at 367.898934 -248.498106 -90)
		(property "Reference" "C491"
			(at 0 0 90)
			(layer "B.SilkS")
			(hide yes)
			(effects
				(font
					(size 1.27 1.27)
				)
				(justify mirror)
			)
		)
		(property "Value" ""
			(at 0 0 90)
			(layer "B.Fab")
			(effects
				(font
					(size 1.27 1.27)
				)
				(justify mirror)
			)
		)
		(duplicate_pad_numbers_are_jumpers no)
		(fp_line
			(start -1.524 0.762)
			(end 1.524 0.762)
			(stroke
				(width 0.1524)
				(type default)
			)
			(layer "B.SilkS")
		)
		(fp_line
			(start 1.524 0.762)
			(end 1.524 -0.762)
			(stroke
				(width 0.1524)
				(type default)
			)
			(layer "B.SilkS")
		)
		(fp_line
			(start -1.524 -0.762)
			(end -1.524 0.762)
			(stroke
				(width 0.1524)
				(type default)
			)
			(layer "B.SilkS")
		)
		(fp_line
			(start 1.524 -0.762)
			(end -1.524 -0.762)
			(stroke
				(width 0.1524)
				(type default)
			)
			(layer "B.SilkS")
		)
		(fp_line
			(start -1.1049 0.724916)
			(end -1.1049 -0.724916)
			(stroke
				(width 0.1)
				(type default)
			)
			(layer "B.Fab")
		)
		(fp_line
			(start 1.1049 0.724916)
			(end -1.1049 0.724916)
			(stroke
				(width 0.1)
				(type default)
			)
			(layer "B.Fab")
		)
		(fp_line
			(start -1.1049 -0.724916)
			(end 1.1049 -0.724916)
			(stroke
				(width 0.1)
				(type default)
			)
			(layer "B.Fab")
		)
		(fp_line
			(start 1.1049 -0.724916)
			(end 1.1049 0.724916)
			(stroke
				(width 0.1)
				(type default)
			)
			(layer "B.Fab")
		)
		(pad "1" smd rect
			(at 0.889 0 270)
			(size 1.016 1.27)
			(layers "B.Cu" "B.Mask" "B.Paste")
			(net "PVCCD_HV_CPU0")
		)
		(pad "2" smd rect
			(at -0.889 0 270)
			(size 1.016 1.27)
			(layers "B.Cu" "B.Mask" "B.Paste")
			(net "GND")
		)
	)
)
